# T6G (Grand Teton) — schematic netlist excerpt (pin names and nets, part order shuffled) for the footprints in the layout excerpt that follows; sources: Cadence DE-HDL packaged netlist, KiCad conversion of 04192023_DAF0TMB3IC0_F0TG_MB_C_brd_V02_OCP.brd

R1674  Q_RES  10 1% CHIP  pkg 0402LF  page 86 : A = I3C_SPD_DDRAF_CPU0_SDA ; B = I3C_SPD_DDRA_CPU0_SDA
C6080  Q_CAP  0.01UF 50V 10% X7R  pkg C0402  page 177 : A = P1V2_AUX ; B = GND

(kicad_pcb
	(version 20260206)
	(generator "pcbnew")
	(generator_version "10.0")
	(general
		(thickness 1.6)
		(legacy_teardrops no)
	)
	(paper "A4")
	(title_block
		(title "04192023_DAF0TMB3IC0_F0TG_MB_C_brd_V02_OCP.brd")
		(comment 1 "Grand Teton / footprints 7068-7069 of 8354")
	)
	(layers
		(0 "F.Cu" signal "TOP")
		(4 "In1.Cu" signal "GND")
		(6 "In2.Cu" signal "IN1")
		(8 "In3.Cu" signal "GND1")
		(10 "In4.Cu" signal "IN2")
		(12 "In5.Cu" signal "GND2")
		(14 "In6.Cu" signal "IN3")
		(16 "In7.Cu" signal "GND3")
		(18 "In8.Cu" signal "VCC")
		(20 "In9.Cu" signal "VCC1")
		(22 "In10.Cu" signal "GND4")
		(24 "In11.Cu" signal "IN4")
		(26 "In12.Cu" signal "GND5")
		(28 "In13.Cu" signal "IN5")
		(30 "In14.Cu" signal "GND6")
		(32 "In15.Cu" signal "IN6")
		(34 "In16.Cu" signal "GND7")
		(2 "B.Cu" signal "BOTTOM")
		(9 "F.Adhes" user "F.Adhesive")
		(11 "B.Adhes" user "B.Adhesive")
		(13 "F.Paste" user "Package Geometry/Pastemask Top")
		(15 "B.Paste" user "Package Geometry/Pastemask Bottom")
		(5 "F.SilkS" user "Ref Des/Silkscreen Top")
		(7 "B.SilkS" user "Ref Des/Silkscreen Bottom")
		(1 "F.Mask" user "Board Geometry/Soldermask Top")
		(3 "B.Mask" user "Board Geometry/Soldermask Bottom")
		(17 "Dwgs.User" user "User.Drawings")
		(19 "Cmts.User" user "User.Comments")
		(21 "Eco1.User" user "User.Eco1")
		(23 "Eco2.User" user "User.Eco2")
		(25 "Edge.Cuts" user "Board Geometry/Outline")
		(27 "Margin" user)
		(31 "F.CrtYd" user "Package Geometry/Place Bound Top")
		(29 "B.CrtYd" user "Package Geometry/Place Bound Bottom")
		(35 "F.Fab" user "Ref Des/Assembly Top")
		(33 "B.Fab" user "Ref Des/Assembly Bottom")
	)
	(footprint ""
		(layer "B.Cu")
		(at 307.34127 -195.95211 180)
		(property "Reference" "R1674"
			(at 0 0 0)
			(layer "B.SilkS")
			(hide yes)
			(effects
				(font
					(size 1.27 1.27)
				)
				(justify mirror)
			)
		)
		(property "Value" ""
			(at 0 0 0)
			(layer "B.Fab")
			(effects
				(font
					(size 1.27 1.27)
				)
				(justify mirror)
			)
		)
		(duplicate_pad_numbers_are_jumpers no)
		(fp_line
			(start 0.7874 0.4064)
			(end 0.7874 -0.4064)
			(stroke
				(width 0.1524)
				(type default)
			)
			(layer "B.SilkS")
		)
		(fp_line
			(start 0.7874 -0.4064)
			(end -0.7874 -0.4064)
			(stroke
				(width 0.1524)
				(type default)
			)
			(layer "B.SilkS")
		)
		(fp_line
			(start -0.7874 0.4064)
			(end 0.7874 0.4064)
			(stroke
				(width 0.1524)
				(type default)
			)
			(layer "B.SilkS")
		)
		(fp_line
			(start -0.7874 -0.4064)
			(end -0.7874 0.4064)
			(stroke
				(width 0.1524)
				(type default)
			)
			(layer "B.SilkS")
		)
		(fp_line
			(start 0.67945 0.3048)
			(end 0.67945 -0.305054)
			(stroke
				(width 0.1)
				(type default)
			)
			(layer "B.Fab")
		)
		(fp_line
			(start 0.67945 -0.305054)
			(end 0.12065 -0.305054)
			(stroke
				(width 0.1)
				(type default)
			)
			(layer "B.Fab")
		)
		(fp_line
			(start 0.12065 0.3048)
			(end 0.67945 0.3048)
			(stroke
				(width 0.1)
				(type default)
			)
			(layer "B.Fab")
		)
		(fp_line
			(start 0.12065 0.2794)
			(end 0.12065 0.3048)
			(stroke
				(width 0.1)
				(type default)
			)
			(layer "B.Fab")
		)
		(fp_line
			(start 0.12065 -0.2794)
			(end -0.12065 -0.2794)
			(stroke
				(width 0.1)
				(type default)
			)
			(layer "B.Fab")
		)
		(fp_line
			(start 0.12065 -0.305054)
			(end 0.12065 -0.2794)
			(stroke
				(width 0.1)
				(type default)
			)
			(layer "B.Fab")
		)
		(fp_line
			(start -0.120396 0.3048)
			(end -0.120396 0.2794)
			(stroke
				(width 0.1)
				(type default)
			)
			(layer "B.Fab")
		)
		(fp_line
			(start -0.120396 0.2794)
			(end 0.12065 0.2794)
			(stroke
				(width 0.1)
				(type default)
			)
			(layer "B.Fab")
		)
		(fp_line
			(start -0.12065 -0.2794)
			(end -0.12065 -0.3048)
			(stroke
				(width 0.1)
				(type default)
			)
			(layer "B.Fab")
		)
		(fp_line
			(start -0.12065 -0.3048)
			(end -0.67945 -0.3048)
			(stroke
				(width 0.1)
				(type default)
			)
			(layer "B.Fab")
		)
		(fp_line
			(start -0.67945 0.3048)
			(end -0.120396 0.3048)
			(stroke
				(width 0.1)
				(type default)
			)
			(layer "B.Fab")
		)
		(fp_line
			(start -0.67945 -0.3048)
			(end -0.67945 0.3048)
			(stroke
				(width 0.1)
				(type default)
			)
			(layer "B.Fab")
		)
		(pad "1" smd circle
			(at 0.40005 0)
			(size 0 0)
			(layers "B.Cu" "B.Mask" "B.Paste")
			(net "I3C_SPD_DDRAF_CPU0_SDA")
		)
		(pad "2" smd circle
			(at -0.40005 0)
			(size 0 0)
			(layers "B.Cu" "B.Mask" "B.Paste")
			(net "I3C_SPD_DDRA_CPU0_SDA")
		)
	)
	(footprint ""
		(layer "B.Cu")
		(at 129.305304 -33.654492)
		(property "Reference" "C6080"
			(at 0 0 0)
			(layer "B.SilkS")
			(hide yes)
			(effects
				(font
					(size 1.27 1.27)
				)
				(justify mirror)
			)
		)
		(property "Value" ""
			(at 0 0 0)
			(layer "B.Fab")
			(effects
				(font
					(size 1.27 1.27)
				)
				(justify mirror)
			)
		)
		(duplicate_pad_numbers_are_jumpers no)
		(fp_line
			(start -0.7874 -0.4064)
			(end -0.7874 0.4064)
			(stroke
				(width 0.1524)
				(type default)
			)
			(layer "B.SilkS")
		)
		(fp_line
			(start -0.7874 0.4064)
			(end 0.7874 0.4064)
			(stroke
				(width 0.1524)
				(type default)
			)
			(layer "B.SilkS")
		)
		(fp_line
			(start 0.7874 -0.4064)
			(end -0.7874 -0.4064)
			(stroke
				(width 0.1524)
				(type default)
			)
			(layer "B.SilkS")
		)
		(fp_line
			(start 0.7874 0.4064)
			(end 0.7874 -0.4064)
			(stroke
				(width 0.1524)
				(type default)
			)
			(layer "B.SilkS")
		)
		(fp_line
			(start -0.67945 -0.3048)
			(end -0.67945 0.3048)
			(stroke
				(width 0.1)
				(type default)
			)
			(layer "B.Fab")
		)
		(fp_line
			(start -0.67945 0.3048)
			(end -0.120396 0.3048)
			(stroke
				(width 0.1)
				(type default)
			)
			(layer "B.Fab")
		)
		(fp_line
			(start -0.12065 -0.3048)
			(end -0.67945 -0.3048)
			(stroke
				(width 0.1)
				(type default)
			)
			(layer "B.Fab")
		)
		(fp_line
			(start -0.12065 -0.2794)
			(end -0.12065 -0.3048)
			(stroke
				(width 0.1)
				(type default)
			)
			(layer "B.Fab")
		)
		(fp_line
			(start -0.120396 0.2794)
			(end 0.12065 0.2794)
			(stroke
				(width 0.1)
				(type default)
			)
			(layer "B.Fab")
		)
		(fp_line
			(start -0.120396 0.3048)
			(end -0.120396 0.2794)
			(stroke
				(width 0.1)
				(type default)
			)
			(layer "B.Fab")
		)
		(fp_line
			(start 0.12065 -0.305054)
			(end 0.12065 -0.2794)
			(stroke
				(width 0.1)
				(type default)
			)
			(layer "B.Fab")
		)
		(fp_line
			(start 0.12065 -0.2794)
			(end -0.12065 -0.2794)
			(stroke
				(width 0.1)
				(type default)
			)
			(layer "B.Fab")
		)
		(fp_line
			(start 0.12065 0.2794)
			(end 0.12065 0.3048)
			(stroke
				(width 0.1)
				(type default)
			)
			(layer "B.Fab")
		)
		(fp_line
			(start 0.12065 0.3048)
			(end 0.67945 0.3048)
			(stroke
				(width 0.1)
				(type default)
			)
			(layer "B.Fab")
		)
		(fp_line
			(start 0.67945 -0.305054)
			(end 0.12065 -0.305054)
			(stroke
				(width 0.1)
				(type default)
			)
			(layer "B.Fab")
		)
		(fp_line
			(start 0.67945 0.3048)
			(end 0.67945 -0.305054)
			(stroke
				(width 0.1)
				(type default)
			)
			(layer "B.Fab")
		)
		(pad "1" smd circle
			(at 0.40005 0 180)
			(size 0 0)
			(layers "B.Cu" "B.Mask" "B.Paste")
			(net "P1V2_AUX")
		)
		(pad "2" smd circle
			(at -0.40005 0 180)
			(size 0 0)
			(layers "B.Cu" "B.Mask" "B.Paste")
			(net "GND")
		)
	)
)
